# T6G (Grand Teton) — schematic netlist excerpt (pin names and nets, part order shuffled) for the footprints in the layout excerpt that follows; sources: Cadence DE-HDL packaged netlist, KiCad conversion of 04192023_DAF0TMB3IC0_F0TG_MB_C_brd_V02_OCP.brd

J28  SCONN288_DDR506112002KQ  IO  pkg DDR288S_1-1VXC  page 100
  VIN_BULK0  = P12V_MEM_CPU1
  RFU0  = NC
  VIN_MGMT  = P3V3_AUX
  HSCL  = I3C_SPD_DDRC_CPU1_SCL
  HSDA  = I3C_SPD_DDRC_CPU1_SDA
  VSS0  = GND
  DQ0_A  = M_C_CPU1_SA_DQ<0>
  VSS1  = GND
  DQ1_A  = M_C_CPU1_SA_DQ<1>
  VSS2  = GND
  DQS0_A_T  = M_C_CPU1_SA_DQS_DP<0>
  DQS0_A_C  = M_C_CPU1_SA_DQS_DN<0>
  VSS3  = GND
  DQ4_A  = M_C_CPU1_SA_DQ<4>
  VSS4  = GND
  DQ5_A  = M_C_CPU1_SA_DQ<5>
  VSS5  = GND
  DQ8_A  = M_C_CPU1_SA_DQ<8>
  VSS6  = GND
  DQ9_A  = M_C_CPU1_SA_DQ<9>
  VSS7  = GND
  DQS1_A_T  = M_C_CPU1_SA_DQS_DP<1>
  DQS1_A_C  = M_C_CPU1_SA_DQS_DN<1>
  VSS8  = GND
  DQ12_A  = M_C_CPU1_SA_DQ<12>
  VSS9  = GND
  DQ13_A  = M_C_CPU1_SA_DQ<13>
  VSS10  = GND
  DQ16_A  = M_C_CPU1_SA_DQ<16>
  VSS11  = GND
  DQ17_A  = M_C_CPU1_SA_DQ<17>
  VSS12  = GND
  DQS2_A_T  = M_C_CPU1_SA_DQS_DP<2>
  DQS2_A_C  = M_C_CPU1_SA_DQS_DN<2>
  VSS13  = GND
  DQ20_A  = M_C_CPU1_SA_DQ<20>
  VSS14  = GND
  DQ21_A  = M_C_CPU1_SA_DQ<21>
  VSS15  = GND
  DQ24_A  = M_C_CPU1_SA_DQ<24>
  VSS16  = GND
  DQ25_A  = M_C_CPU1_SA_DQ<25>
  VSS17  = GND
  DQS3_A_T  = M_C_CPU1_SA_DQS_DP<3>
  DQS3_A_C  = M_C_CPU1_SA_DQS_DN<3>
  VSS18  = GND
  DQ28_A  = M_C_CPU1_SA_DQ<28>
  VSS19  = GND
  DQ29_A  = M_C_CPU1_SA_DQ<29>
  VSS20  = GND
  CB0_A  = M_C_CPU1_SA_CB<0>
  VSS21  = GND
  CB1_A  = M_C_CPU1_SA_CB<1>
  VSS22  = GND
  DQS4_A_T  = M_C_CPU1_SA_DQS_DP<4>
  DQS4_A_C  = M_C_CPU1_SA_DQS_DN<4>
  VSS23  = GND
  CB4_A  = M_C_CPU1_SA_CB<4>
  VSS24  = GND
  CB5_A  = M_C_CPU1_SA_CB<5>
  VSS25  = GND
  ALERT_N  = M_C_CPU1_ALERT_N
  VSS26  = GND
  CS0_A_N  = M_C_CPU1_SA_CS_N<0>
  VSS27  = GND
  CA0_A  = M_C_CPU1_SA_CA<0>
  VSS28  = GND
  CA2_A  = M_C_CPU1_SA_CA<2>
  VSS29  = GND
  CA4_A  = M_C_CPU1_SA_CA<4>
  VSS30  = GND
  CA6_A  = M_C_CPU1_SA_CA<6>
  VSS31  = GND
  PAR_A  = M_C_CPU1_SA_PAR
  VSS32  = GND
  CA0_B  = M_C_CPU1_SB_CA<0>
  VSS33  = GND
  CA2_B  = M_C_CPU1_SB_CA<2>
  VSS34  = GND
  CA4_B  = M_C_CPU1_SB_CA<4>
  VSS35  = GND
  CA6_B  = M_C_CPU1_SB_CA<6>
  VSS36  = GND
  CS0_B_N  = M_C_CPU1_SB_CS_N<0>
  VSS37  = GND
  \lbd||rsp_a_n\  = M_C_CPU1_SA_RSP<0>
  \lbs||rsp_b_n\  = M_C_CPU1_SB_RSP<0>
  VSS38  = GND
  CB4_B  = M_C_CPU1_SB_CB<4>
  VSS39  = GND
  CB5_B  = M_C_CPU1_SB_CB<5>
  VSS40  = GND
  \dqs9_b_t||tdqs9_b_t||dbi4_b_n\  = M_C_CPU1_SB_DQS_DP<9>
  \dqs9_b_c||tdqs9_b_c\  = M_C_CPU1_SB_DQS_DN<9>
  VSS41  = GND
  CB0_B  = M_C_CPU1_SB_CB<0>
  VSS42  = GND
  CB1_B  = M_C_CPU1_SB_CB<1>
  VSS43  = GND
  DQ0_B  = M_C_CPU1_SB_DQ<0>
  VSS44  = GND
  DQ1_B  = M_C_CPU1_SB_DQ<1>
  VSS45  = GND
  DQS0_B_T  = M_C_CPU1_SB_DQS_DP<0>
  DQS0_B_C  = M_C_CPU1_SB_DQS_DN<0>
  VSS46  = GND
  DQ4_B  = M_C_CPU1_SB_DQ<4>
  VSS47  = GND
  DQ5_B  = M_C_CPU1_SB_DQ<5>
  VSS48  = GND
  DQ8_B  = M_C_CPU1_SB_DQ<8>
  VSS49  = GND
  DQ9_B  = M_C_CPU1_SB_DQ<9>
  VSS50  = GND
  DQS1_B_T  = M_C_CPU1_SB_DQS_DP<1>
  DQS1_B_C  = M_C_CPU1_SB_DQS_DN<1>
  VSS51  = GND
  DQ12_B  = M_C_CPU1_SB_DQ<12>
  VSS52  = GND
  DQ13_B  = M_C_CPU1_SB_DQ<13>
  VSS53  = GND
  DQ16_B  = M_C_CPU1_SB_DQ<16>
  VSS54  = GND
  DQ17_B  = M_C_CPU1_SB_DQ<17>
  VSS55  = GND
  DQS2_B_T  = M_C_CPU1_SB_DQS_DP<2>
  DQS2_B_C  = M_C_CPU1_SB_DQS_DN<2>
  VSS56  = GND
  DQ20_B  = M_C_CPU1_SB_DQ<20>
  VSS57  = GND
  DQ21_B  = M_C_CPU1_SB_DQ<21>
  VSS58  = GND
  DQ24_B  = M_C_CPU1_SB_DQ<24>
  VSS59  = GND
  DQ25_B  = M_C_CPU1_SB_DQ<25>
  VSS60  = GND
  DQS3_B_T  = M_C_CPU1_SB_DQS_DP<3>
  DQS3_B_C  = M_C_CPU1_SB_DQS_DN<3>
  VSS61  = GND
  DQ28_B  = M_C_CPU1_SB_DQ<28>
  VSS62  = GND
  DQ29_B  = M_C_CPU1_SB_DQ<29>
  VSS63  = GND
  RFU1  = NC
  VIN_BULK1  = P12V_MEM_CPU1
  VIN_BULK2  = P12V_MEM_CPU1
  \pwr_good||fail_n\  = PWRGD_CHC_CPU1_DIMM
  HAS  = PD_CHC_CPU1_DIMM_SAA
  RFU2  = NC
  RFU3  = NC
  VSS64  = GND
  DQ2_A  = M_C_CPU1_SA_DQ<2>
  VSS65  = GND
  DQ3_A  = M_C_CPU1_SA_DQ<3>
  VSS66  = GND
  \dqs5_a_c||tdqs5_a_c||dqs5_a_t||tdqs5_a_t\  = M_C_CPU1_SA_DQS_DN<5>
  \dqs5_a_t||tdqs5_a_t\  = M_C_CPU1_SA_DQS_DP<5>
  VSS67  = GND
  DQ6_A  = M_C_CPU1_SA_DQ<6>
  VSS68  = GND
  DQ7_A  = M_C_CPU1_SA_DQ<7>
  VSS69  = GND
  DQ10_A  = M_C_CPU1_SA_DQ<10>
  VSS70  = GND
  DQ11_A  = M_C_CPU1_SA_DQ<11>
  VSS71  = GND
  \dqs6_a_c||tdqs6_a_c||dqs6_a_t||tdqs6_a_t\  = M_C_CPU1_SA_DQS_DN<6>
  \dqs6_a_t||tdqs6_a_t\  = M_C_CPU1_SA_DQS_DP<6>
  VSS72  = GND
  DQ14_A  = M_C_CPU1_SA_DQ<14>
  VSS73  = GND
  DQ15_A  = M_C_CPU1_SA_DQ<15>
  VSS74  = GND
  DQ18_A  = M_C_CPU1_SA_DQ<18>
  VSS75  = GND
  DQ19_A  = M_C_CPU1_SA_DQ<19>
  VSS76  = GND
  \dqs7_a_c||tdqs7_a_c\  = M_C_CPU1_SA_DQS_DN<7>
  \dqs7_a_t||tdqs7_a_t\  = M_C_CPU1_SA_DQS_DP<7>
  VSS77  = GND
  DQ22_A  = M_C_CPU1_SA_DQ<22>
  VSS78  = GND
  DQ23_A  = M_C_CPU1_SA_DQ<23>
  VSS79  = GND
  DQ26_A  = M_C_CPU1_SA_DQ<26>
  VSS80  = GND
  DQ27_A  = M_C_CPU1_SA_DQ<27>
  VSS81  = GND
  \dqs8_a_c||tdqs8_a_c\  = M_C_CPU1_SA_DQS_DN<8>
  \dqs8_a_t||tdqs8_a_t\  = M_C_CPU1_SA_DQS_DP<8>
  VSS82  = GND
  DQ30_A  = M_C_CPU1_SA_DQ<30>
  VSS83  = GND
  DQ31_A  = M_C_CPU1_SA_DQ<31>
  VSS84  = GND
  CB2_A  = M_C_CPU1_SA_CB<2>
  VSS85  = GND
  CB3_A  = M_C_CPU1_SA_CB<3>
  VSS86  = GND
  \dqs9_a_c||tdqs9_a_c\  = M_C_CPU1_SA_DQS_DN<9>
  \dqs9_a_t||tdqs9_a_t\  = M_C_CPU1_SA_DQS_DP<9>
  VSS87  = GND
  CB6_A  = M_C_CPU1_SA_CB<6>
  VSS88  = GND
  CB7_A  = M_C_CPU1_SA_CB<7>
  VSS89  = GND
  RESET_N  = M_C_CPU1_RESET_N
  VSS90  = GND
  CS1_A_N  = M_C_CPU1_SA_CS_N<1>
  VSS91  = GND
  CA1_A  = M_C_CPU1_SA_CA<1>
  VSS92  = GND
  CA3_A  = M_C_CPU1_SA_CA<3>
  VSS93  = GND
  CA5_A  = M_C_CPU1_SA_CA<5>
  VSS94  = GND
  CK_T  = M_C_CPU1_CLK_DP<0>
  CK_C  = M_C_CPU1_CLK_DN<0>
  VSS95  = GND
  RFU4  = NC
  CA1_B  = M_C_CPU1_SB_CA<1>
  VSS96  = GND
  CA3_B  = M_C_CPU1_SB_CA<3>
  VSS97  = GND
  CA5_B  = M_C_CPU1_SB_CA<5>
  VSS98  = GND
  PAR_B  = M_C_CPU1_SB_PAR
  VSS99  = GND
  CS1_B_N  = M_C_CPU1_SB_CS_N<1>
  VSS100  = GND
  RFU5  = NC
  RFU6  = NC
  VSS101  = GND
  CB6_B  = M_C_CPU1_SB_CB<6>
  VSS102  = GND
  CB7_B  = M_C_CPU1_SB_CB<7>
  VSS103  = GND
  DQS4_B_C  = M_C_CPU1_SB_DQS_DN<4>
  DQS4_B_T  = M_C_CPU1_SB_DQS_DP<4>
  VSS104  = GND
  CB2_B  = M_C_CPU1_SB_CB<2>
  VSS105  = GND
  CB3_B  = M_C_CPU1_SB_CB<3>
  VSS106  = GND
  DQ2_B  = M_C_CPU1_SB_DQ<2>
  VSS107  = GND
  DQ3_B  = M_C_CPU1_SB_DQ<3>
  VSS108  = GND
  \dqs5_b_c||tdqs5_b_c\  = M_C_CPU1_SB_DQS_DN<5>
  \dqs5_b_t||tdqs5_b_t\  = M_C_CPU1_SB_DQS_DP<5>
  VSS109  = GND
  DQ6_B  = M_C_CPU1_SB_DQ<6>
  VSS110  = GND
  DQ7_B  = M_C_CPU1_SB_DQ<7>
  VSS111  = GND
  DQ10_B  = M_C_CPU1_SB_DQ<10>
  VSS112  = GND
  DQ11_B  = M_C_CPU1_SB_DQ<11>
  VSS113  = GND
  \dqs6_b_c||tdqs6_b_c\  = M_C_CPU1_SB_DQS_DN<6>
  \dqs6_b_t||tdqs6_b_t\  = M_C_CPU1_SB_DQS_DP<6>
  VSS114  = GND
  DQ14_B  = M_C_CPU1_SB_DQ<14>
  VSS115  = GND
  DQ15_B  = M_C_CPU1_SB_DQ<15>
  VSS116  = GND
  DQ18_B  = M_C_CPU1_SB_DQ<18>
  VSS117  = GND
  DQ19_B  = M_C_CPU1_SB_DQ<19>
  VSS118  = GND
  \dqs7_b_c||tdqs7_b_c\  = M_C_CPU1_SB_DQS_DN<7>
  \dqs7_b_t||tdqs7_b_t\  = M_C_CPU1_SB_DQS_DP<7>
  VSS119  = GND
  DQ22_B  = M_C_CPU1_SB_DQ<22>
  VSS120  = GND
  DQ23_B  = M_C_CPU1_SB_DQ<23>
  VSS121  = GND
  DQ26_B  = M_C_CPU1_SB_DQ<26>
  VSS122  = GND
  DQ27_B  = M_C_CPU1_SB_DQ<27>
  VSS123  = GND
  \dqs8_b_c||tdqs8_b_c\  = M_C_CPU1_SB_DQS_DN<8>
  \dqs8_b_t||tdqs8_b_t\  = M_C_CPU1_SB_DQS_DP<8>
  VSS124  = GND
  DQ30_B  = M_C_CPU1_SB_DQ<30>
  VSS125  = GND
  DQ31_B  = M_C_CPU1_SB_DQ<31>
  VSS126  = GND
  G1  = GND
  G2  = GND
  G3  = GND

(kicad_pcb
	(version 20260206)
	(generator "pcbnew")
	(generator_version "10.0")
	(general
		(thickness 1.6)
		(legacy_teardrops no)
	)
	(paper "A4")
	(title_block
		(title "04192023_DAF0TMB3IC0_F0TG_MB_C_brd_V02_OCP.brd")
		(comment 1 "Grand Teton / footprint 4188 of 8354 (J28), pads 277-291 of 291")
	)
	(layers
		(0 "F.Cu" signal "TOP")
		(4 "In1.Cu" signal "GND")
		(6 "In2.Cu" signal "IN1")
		(8 "In3.Cu" signal "GND1")
		(10 "In4.Cu" signal "IN2")
		(12 "In5.Cu" signal "GND2")
		(14 "In6.Cu" signal "IN3")
		(16 "In7.Cu" signal "GND3")
		(18 "In8.Cu" signal "VCC")
		(20 "In9.Cu" signal "VCC1")
		(22 "In10.Cu" signal "GND4")
		(24 "In11.Cu" signal "IN4")
		(26 "In12.Cu" signal "GND5")
		(28 "In13.Cu" signal "IN5")
		(30 "In14.Cu" signal "GND6")
		(32 "In15.Cu" signal "IN6")
		(34 "In16.Cu" signal "GND7")
		(2 "B.Cu" signal "BOTTOM")
		(9 "F.Adhes" user "F.Adhesive")
		(11 "B.Adhes" user "B.Adhesive")
		(13 "F.Paste" user "Package Geometry/Pastemask Top")
		(15 "B.Paste" user "Package Geometry/Pastemask Bottom")
		(5 "F.SilkS" user "Ref Des/Silkscreen Top")
		(7 "B.SilkS" user "Ref Des/Silkscreen Bottom")
		(1 "F.Mask" user "Board Geometry/Soldermask Top")
		(3 "B.Mask" user "Board Geometry/Soldermask Bottom")
		(17 "Dwgs.User" user "User.Drawings")
		(19 "Cmts.User" user "User.Comments")
		(21 "Eco1.User" user "User.Eco1")
		(23 "Eco2.User" user "User.Eco2")
		(25 "Edge.Cuts" user "Board Geometry/Outline")
		(27 "Margin" user)
		(31 "F.CrtYd" user "Package Geometry/Place Bound Top")
		(29 "B.CrtYd" user "Package Geometry/Place Bound Bottom")
		(35 "F.Fab" user "Ref Des/Assembly Top")
		(33 "B.Fab" user "Ref Des/Assembly Bottom")
	)
	(footprint ""
		(layer "F.Cu")
		(at 42.289984 -255.560322 180)
		(property "Reference" "J28"
			(at -2.876296 -82.230976 0)
			(unlocked yes)
			(layer "F.SilkS")
			(effects
				(font
					(size 0.7874 0.5842)
					(thickness 0.1524)
				)
			)
		)
		(property "Value" ""
			(at 0 0 180)
			(layer "F.Fab")
			(effects
				(font
					(size 1.27 1.27)
				)
			)
		)
		(duplicate_pad_numbers_are_jumpers no)
		(pad "277" smd rect
			(at 2.050034 53.975 90)
			(size 0.519938 1.4986)
			(layers "F.Cu" "F.Mask" "F.Paste")
			(net "GND")
		)
		(pad "278" smd rect
			(at 2.050034 54.824884 90)
			(size 0.519938 1.4986)
			(layers "F.Cu" "F.Mask" "F.Paste")
			(net "M_C_CPU1_SB_DQ<26>")
		)
		(pad "279" smd rect
			(at 2.050034 55.675022 90)
			(size 0.519938 1.4986)
			(layers "F.Cu" "F.Mask" "F.Paste")
			(net "GND")
		)
		(pad "280" smd rect
			(at 2.050034 56.524906 90)
			(size 0.519938 1.4986)
			(layers "F.Cu" "F.Mask" "F.Paste")
			(net "M_C_CPU1_SB_DQ<27>")
		)
		(pad "281" smd rect
			(at 2.050034 57.375044 90)
			(size 0.519938 1.4986)
			(layers "F.Cu" "F.Mask" "F.Paste")
			(net "GND")
		)
		(pad "282" smd rect
			(at 2.050034 58.224928 90)
			(size 0.519938 1.4986)
			(layers "F.Cu" "F.Mask" "F.Paste")
			(net "M_C_CPU1_SB_DQS_DN<8>")
		)
		(pad "283" smd rect
			(at 2.050034 59.075066 90)
			(size 0.519938 1.4986)
			(layers "F.Cu" "F.Mask" "F.Paste")
			(net "M_C_CPU1_SB_DQS_DP<8>")
		)
		(pad "284" smd rect
			(at 2.050034 59.92495 90)
			(size 0.519938 1.4986)
			(layers "F.Cu" "F.Mask" "F.Paste")
			(net "GND")
		)
		(pad "285" smd rect
			(at 2.050034 60.775088 90)
			(size 0.519938 1.4986)
			(layers "F.Cu" "F.Mask" "F.Paste")
			(net "M_C_CPU1_SB_DQ<30>")
		)
		(pad "286" smd rect
			(at 2.050034 61.624972 90)
			(size 0.519938 1.4986)
			(layers "F.Cu" "F.Mask" "F.Paste")
			(net "GND")
		)
		(pad "287" smd rect
			(at 2.050034 62.47511 90)
			(size 0.519938 1.4986)
			(layers "F.Cu" "F.Mask" "F.Paste")
			(net "M_C_CPU1_SB_DQ<31>")
		)
		(pad "288" smd rect
			(at 2.050034 63.324994 90)
			(size 0.519938 1.4986)
			(layers "F.Cu" "F.Mask" "F.Paste")
			(net "GND")
		)
		(pad "G1" thru_hole oval
			(at 0 -68.97497 90)
			(size 1.7272 3.4798)
			(drill oval 1.2192 2.4638)
			(layers "*.Cu" "*.Mask")
			(remove_unused_layers no)
			(net "GND")
			(clearance 0.127)
			(thermal_gap 0.127)
		)
		(pad "G2" thru_hole oval
			(at 0 3.875024 90)
			(size 1.7272 3.4798)
			(drill oval 1.2192 2.4638)
			(layers "*.Cu" "*.Mask")
			(remove_unused_layers no)
			(net "GND")
			(clearance 0.127)
			(thermal_gap 0.127)
		)
		(pad "G3" thru_hole oval
			(at 0 68.97497 90)
			(size 1.7272 3.4798)
			(drill oval 1.2192 2.4638)
			(layers "*.Cu" "*.Mask")
			(remove_unused_layers no)
			(net "GND")
			(clearance 0.127)
			(thermal_gap 0.127)
		)
	)
)
